(kicad_pcb
	(version 20260206)
	(generator "pcbnew")
	(generator_version "10.0")
	(general
		(thickness 1.6)
		(legacy_teardrops no)
	)
	(paper "A4")
	(title_block
		(title "04192023_DAF0TMB3IC0_F0TG_MB_C_brd_V02_OCP.brd")
		(comment 1 "Grand Teton / footprints 6089-6095 of 8354")
	)
	(layers
		(0 "F.Cu" signal "TOP")
		(4 "In1.Cu" signal "GND")
		(6 "In2.Cu" signal "IN1")
		(8 "In3.Cu" signal "GND1")
		(10 "In4.Cu" signal "IN2")
		(12 "In5.Cu" signal "GND2")
		(14 "In6.Cu" signal "IN3")
		(16 "In7.Cu" signal "GND3")
		(18 "In8.Cu" signal "VCC")
		(20 "In9.Cu" signal "VCC1")
		(22 "In10.Cu" signal "GND4")
		(24 "In11.Cu" signal "IN4")
		(26 "In12.Cu" signal "GND5")
		(28 "In13.Cu" signal "IN5")
		(30 "In14.Cu" signal "GND6")
		(32 "In15.Cu" signal "IN6")
		(34 "In16.Cu" signal "GND7")
		(2 "B.Cu" signal "BOTTOM")
		(9 "F.Adhes" user "F.Adhesive")
		(11 "B.Adhes" user "B.Adhesive")
		(13 "F.Paste" user "Package Geometry/Pastemask Top")
		(15 "B.Paste" user "Package Geometry/Pastemask Bottom")
		(5 "F.SilkS" user "Ref Des/Silkscreen Top")
		(7 "B.SilkS" user "Ref Des/Silkscreen Bottom")
		(1 "F.Mask" user "Board Geometry/Soldermask Top")
		(3 "B.Mask" user "Board Geometry/Soldermask Bottom")
		(17 "Dwgs.User" user "User.Drawings")
		(19 "Cmts.User" user "User.Comments")
		(21 "Eco1.User" user "User.Eco1")
		(23 "Eco2.User" user "User.Eco2")
		(25 "Edge.Cuts" user "Board Geometry/Outline")
		(27 "Margin" user)
		(31 "F.CrtYd" user "Package Geometry/Place Bound Top")
		(29 "B.CrtYd" user "Package Geometry/Place Bound Bottom")
		(35 "F.Fab" user "Ref Des/Assembly Top")
		(33 "B.Fab" user "Ref Des/Assembly Bottom")
	)
	(footprint ""
		(layer "B.Cu")
		(at 98.336354 -189.453012 90)
		(property "Reference" "PC275"
			(at 5.837936 0.970534 270)
			(unlocked yes)
			(layer "B.SilkS")
			(effects
				(font
					(size 0.7874 0.5842)
					(thickness 0.1524)
				)
				(justify left mirror)
			)
		)
		(property "Value" ""
			(at 0 0 90)
			(layer "B.Fab")
			(effects
				(font
					(size 1.27 1.27)
				)
				(justify mirror)
			)
		)
		(duplicate_pad_numbers_are_jumpers no)
		(fp_line
			(start 4.533392 -2.249932)
			(end -4.533392 -2.249932)
			(stroke
				(width 0.1524)
				(type default)
			)
			(layer "B.SilkS")
		)
		(fp_line
			(start -4.533392 -2.249932)
			(end -4.533392 2.249932)
			(stroke
				(width 0.1524)
				(type default)
			)
			(layer "B.SilkS")
		)
		(fp_line
			(start 4.533392 2.249932)
			(end 4.533392 -2.249932)
			(stroke
				(width 0.1524)
				(type default)
			)
			(layer "B.SilkS")
		)
		(fp_line
			(start -4.533392 2.249932)
			(end 4.533392 2.249932)
			(stroke
				(width 0.1524)
				(type default)
			)
			(layer "B.SilkS")
		)
		(fp_rect
			(start 4.533392 -2.326132)
			(end 5.39242 2.326132)
			(stroke
				(width 0)
				(type default)
			)
			(fill yes)
			(layer "B.SilkS")
		)
		(fp_line
			(start 3.750056 -2.249932)
			(end -3.750056 -2.249932)
			(stroke
				(width 0.1)
				(type default)
			)
			(layer "B.Fab")
		)
		(fp_line
			(start -3.750056 -2.249932)
			(end -3.750056 2.249932)
			(stroke
				(width 0.1)
				(type default)
			)
			(layer "B.Fab")
		)
		(fp_line
			(start 3.750056 2.249932)
			(end 3.750056 -2.249932)
			(stroke
				(width 0.1)
				(type default)
			)
			(layer "B.Fab")
		)
		(fp_line
			(start -3.750056 2.249932)
			(end 3.750056 2.249932)
			(stroke
				(width 0.1)
				(type default)
			)
			(layer "B.Fab")
		)
		(fp_text user "+"
			(at 6.322314 0.786384 0)
			(unlocked yes)
			(layer "B.SilkS")
			(effects
				(font
					(size 1.905 1.4224)
					(thickness 0.1524)
				)
				(justify left mirror)
			)
		)
		(fp_text user "-"
			(at -5.105908 0.958088 90)
			(unlocked yes)
			(layer "B.SilkS")
			(effects
				(font
					(size 1.905 1.4224)
					(thickness 0.1524)
				)
				(justify left mirror)
			)
		)
		(fp_text user "-"
			(at -4.8514 -0.14605 90)
			(unlocked yes)
			(layer "B.Fab")
			(effects
				(font
					(size 1.905 1.4224)
					(thickness 0.1524)
				)
				(justify left mirror)
			)
		)
		(fp_text user "+"
			(at 6.322314 0.786384 0)
			(unlocked yes)
			(layer "B.Fab")
			(effects
				(font
					(size 1.905 1.4224)
					(thickness 0.1524)
				)
				(justify left mirror)
			)
		)
		(pad "1" smd rect
			(at 3.199892 0 270)
			(size 2.413 2.8194)
			(layers "B.Cu" "B.Mask" "B.Paste")
			(net "PVDDCR_CPU0_P1")
		)
		(pad "2" smd rect
			(at -3.199892 0 270)
			(size 2.413 2.8194)
			(layers "B.Cu" "B.Mask" "B.Paste")
			(net "GND")
		)
	)
	(footprint ""
		(layer "B.Cu")
		(at 365.835692 -262.204962)
		(property "Reference" "C3892"
			(at 0 0 0)
			(layer "B.SilkS")
			(hide yes)
			(effects
				(font
					(size 1.27 1.27)
				)
				(justify mirror)
			)
		)
		(property "Value" ""
			(at 0 0 0)
			(layer "B.Fab")
			(effects
				(font
					(size 1.27 1.27)
				)
				(justify mirror)
			)
		)
		(duplicate_pad_numbers_are_jumpers no)
		(fp_line
			(start -0.7874 -0.4064)
			(end -0.7874 0.4064)
			(stroke
				(width 0.1524)
				(type default)
			)
			(layer "B.SilkS")
		)
		(fp_line
			(start -0.7874 0.4064)
			(end 0.7874 0.4064)
			(stroke
				(width 0.1524)
				(type default)
			)
			(layer "B.SilkS")
		)
		(fp_line
			(start 0.7874 -0.4064)
			(end -0.7874 -0.4064)
			(stroke
				(width 0.1524)
				(type default)
			)
			(layer "B.SilkS")
		)
		(fp_line
			(start 0.7874 0.4064)
			(end 0.7874 -0.4064)
			(stroke
				(width 0.1524)
				(type default)
			)
			(layer "B.SilkS")
		)
		(fp_line
			(start -0.67945 -0.3048)
			(end -0.67945 0.3048)
			(stroke
				(width 0.1)
				(type default)
			)
			(layer "B.Fab")
		)
		(fp_line
			(start -0.67945 0.3048)
			(end -0.120396 0.3048)
			(stroke
				(width 0.1)
				(type default)
			)
			(layer "B.Fab")
		)
		(fp_line
			(start -0.12065 -0.3048)
			(end -0.67945 -0.3048)
			(stroke
				(width 0.1)
				(type default)
			)
			(layer "B.Fab")
		)
		(fp_line
			(start -0.12065 -0.2794)
			(end -0.12065 -0.3048)
			(stroke
				(width 0.1)
				(type default)
			)
			(layer "B.Fab")
		)
		(fp_line
			(start -0.120396 0.2794)
			(end 0.12065 0.2794)
			(stroke
				(width 0.1)
				(type default)
			)
			(layer "B.Fab")
		)
		(fp_line
			(start -0.120396 0.3048)
			(end -0.120396 0.2794)
			(stroke
				(width 0.1)
				(type default)
			)
			(layer "B.Fab")
		)
		(fp_line
			(start 0.12065 -0.305054)
			(end 0.12065 -0.2794)
			(stroke
				(width 0.1)
				(type default)
			)
			(layer "B.Fab")
		)
		(fp_line
			(start 0.12065 -0.2794)
			(end -0.12065 -0.2794)
			(stroke
				(width 0.1)
				(type default)
			)
			(layer "B.Fab")
		)
		(fp_line
			(start 0.12065 0.2794)
			(end 0.12065 0.3048)
			(stroke
				(width 0.1)
				(type default)
			)
			(layer "B.Fab")
		)
		(fp_line
			(start 0.12065 0.3048)
			(end 0.67945 0.3048)
			(stroke
				(width 0.1)
				(type default)
			)
			(layer "B.Fab")
		)
		(fp_line
			(start 0.67945 -0.305054)
			(end 0.12065 -0.305054)
			(stroke
				(width 0.1)
				(type default)
			)
			(layer "B.Fab")
		)
		(fp_line
			(start 0.67945 0.3048)
			(end 0.67945 -0.305054)
			(stroke
				(width 0.1)
				(type default)
			)
			(layer "B.Fab")
		)
		(pad "1" smd circle
			(at 0.40005 0 180)
			(size 0 0)
			(layers "B.Cu" "B.Mask" "B.Paste")
			(net "PVDD11_S3_P0")
		)
		(pad "2" smd circle
			(at -0.40005 0 180)
			(size 0 0)
			(layers "B.Cu" "B.Mask" "B.Paste")
			(net "GND")
		)
	)
	(footprint ""
		(layer "B.Cu")
		(at 214.884 -330.708)
		(property "Reference" "R6775"
			(at 0 0 0)
			(layer "B.SilkS")
			(hide yes)
			(effects
				(font
					(size 1.27 1.27)
				)
				(justify mirror)
			)
		)
		(property "Value" ""
			(at 0 0 0)
			(layer "B.Fab")
			(effects
				(font
					(size 1.27 1.27)
				)
				(justify mirror)
			)
		)
		(duplicate_pad_numbers_are_jumpers no)
		(fp_line
			(start -0.32512 -0.175006)
			(end -0.32512 0.175006)
			(stroke
				(width 0.1)
				(type default)
			)
			(layer "B.Fab")
		)
		(fp_line
			(start -0.32512 0.175006)
			(end 0.32512 0.175006)
			(stroke
				(width 0.1)
				(type default)
			)
			(layer "B.Fab")
		)
		(fp_line
			(start 0.32512 -0.175006)
			(end -0.32512 -0.175006)
			(stroke
				(width 0.1)
				(type default)
			)
			(layer "B.Fab")
		)
		(fp_line
			(start 0.32512 0.175006)
			(end 0.32512 -0.175006)
			(stroke
				(width 0.1)
				(type default)
			)
			(layer "B.Fab")
		)
		(pad "1" smd rect
			(at 0.2667 0 180)
			(size 0.3048 0.381)
			(layers "B.Cu" "B.Mask" "B.Paste")
			(net "RT_SMB_MUX_ADDR0")
		)
		(pad "2" smd rect
			(at -0.2667 0)
			(size 0.3048 0.381)
			(layers "B.Cu" "B.Mask" "B.Paste")
			(net "GND")
		)
	)
	(footprint ""
		(layer "B.Cu")
		(at 326.64527 -395.466062 -90)
		(property "Reference" "C502"
			(at 0 0 90)
			(layer "B.SilkS")
			(hide yes)
			(effects
				(font
					(size 1.27 1.27)
				)
				(justify mirror)
			)
		)
		(property "Value" ""
			(at 0 0 90)
			(layer "B.Fab")
			(effects
				(font
					(size 1.27 1.27)
				)
				(justify mirror)
			)
		)
		(duplicate_pad_numbers_are_jumpers no)
		(fp_line
			(start -1.524 0.762)
			(end 1.524 0.762)
			(stroke
				(width 0.1524)
				(type default)
			)
			(layer "B.SilkS")
		)
		(fp_line
			(start 1.524 0.762)
			(end 1.524 -0.762)
			(stroke
				(width 0.1524)
				(type default)
			)
			(layer "B.SilkS")
		)
		(fp_line
			(start -1.524 -0.762)
			(end -1.524 0.762)
			(stroke
				(width 0.1524)
				(type default)
			)
			(layer "B.SilkS")
		)
		(fp_line
			(start 1.524 -0.762)
			(end -1.524 -0.762)
			(stroke
				(width 0.1524)
				(type default)
			)
			(layer "B.SilkS")
		)
		(fp_line
			(start -1.1049 0.724916)
			(end -1.1049 -0.724916)
			(stroke
				(width 0.1)
				(type default)
			)
			(layer "B.Fab")
		)
		(fp_line
			(start 1.1049 0.724916)
			(end -1.1049 0.724916)
			(stroke
				(width 0.1)
				(type default)
			)
			(layer "B.Fab")
		)
		(fp_line
			(start -1.1049 -0.724916)
			(end 1.1049 -0.724916)
			(stroke
				(width 0.1)
				(type default)
			)
			(layer "B.Fab")
		)
		(fp_line
			(start 1.1049 -0.724916)
			(end 1.1049 0.724916)
			(stroke
				(width 0.1)
				(type default)
			)
			(layer "B.Fab")
		)
		(pad "1" smd rect
			(at 0.889 0 270)
			(size 1.016 1.27)
			(layers "B.Cu" "B.Mask" "B.Paste")
			(net "P1V8_CPU0_RT_1D")
		)
		(pad "2" smd rect
			(at -0.889 0 270)
			(size 1.016 1.27)
			(layers "B.Cu" "B.Mask" "B.Paste")
			(net "GND")
		)
	)
	(footprint ""
		(layer "B.Cu")
		(at 355.616002 -256.012188 -90)
		(property "Reference" "C2568"
			(at 0 0 90)
			(layer "B.SilkS")
			(hide yes)
			(effects
				(font
					(size 1.27 1.27)
				)
				(justify mirror)
			)
		)
		(property "Value" ""
			(at 0 0 90)
			(layer "B.Fab")
			(effects
				(font
					(size 1.27 1.27)
				)
				(justify mirror)
			)
		)
		(duplicate_pad_numbers_are_jumpers no)
		(fp_line
			(start -0.7874 0.4064)
			(end 0.7874 0.4064)
			(stroke
				(width 0.1524)
				(type default)
			)
			(layer "B.SilkS")
		)
		(fp_line
			(start 0.7874 0.4064)
			(end 0.7874 -0.4064)
			(stroke
				(width 0.1524)
				(type default)
			)
			(layer "B.SilkS")
		)
		(fp_line
			(start -0.7874 -0.4064)
			(end -0.7874 0.4064)
			(stroke
				(width 0.1524)
				(type default)
			)
			(layer "B.SilkS")
		)
		(fp_line
			(start 0.7874 -0.4064)
			(end -0.7874 -0.4064)
			(stroke
				(width 0.1524)
				(type default)
			)
			(layer "B.SilkS")
		)
		(fp_line
			(start -0.67945 0.3048)
			(end -0.120396 0.3048)
			(stroke
				(width 0.1)
				(type default)
			)
			(layer "B.Fab")
		)
		(fp_line
			(start -0.120396 0.3048)
			(end -0.120396 0.2794)
			(stroke
				(width 0.1)
				(type default)
			)
			(layer "B.Fab")
		)
		(fp_line
			(start 0.12065 0.3048)
			(end 0.67945 0.3048)
			(stroke
				(width 0.1)
				(type default)
			)
			(layer "B.Fab")
		)
		(fp_line
			(start 0.67945 0.3048)
			(end 0.67945 -0.305054)
			(stroke
				(width 0.1)
				(type default)
			)
			(layer "B.Fab")
		)
		(fp_line
			(start -0.120396 0.2794)
			(end 0.12065 0.2794)
			(stroke
				(width 0.1)
				(type default)
			)
			(layer "B.Fab")
		)
		(fp_line
			(start 0.12065 0.2794)
			(end 0.12065 0.3048)
			(stroke
				(width 0.1)
				(type default)
			)
			(layer "B.Fab")
		)
		(fp_line
			(start -0.12065 -0.2794)
			(end -0.12065 -0.3048)
			(stroke
				(width 0.1)
				(type default)
			)
			(layer "B.Fab")
		)
		(fp_line
			(start 0.12065 -0.2794)
			(end -0.12065 -0.2794)
			(stroke
				(width 0.1)
				(type default)
			)
			(layer "B.Fab")
		)
		(fp_line
			(start -0.67945 -0.3048)
			(end -0.67945 0.3048)
			(stroke
				(width 0.1)
				(type default)
			)
			(layer "B.Fab")
		)
		(fp_line
			(start -0.12065 -0.3048)
			(end -0.67945 -0.3048)
			(stroke
				(width 0.1)
				(type default)
			)
			(layer "B.Fab")
		)
		(fp_line
			(start 0.12065 -0.305054)
			(end 0.12065 -0.2794)
			(stroke
				(width 0.1)
				(type default)
			)
			(layer "B.Fab")
		)
		(fp_line
			(start 0.67945 -0.305054)
			(end 0.12065 -0.305054)
			(stroke
				(width 0.1)
				(type default)
			)
			(layer "B.Fab")
		)
		(pad "1" smd circle
			(at 0.40005 0 90)
			(size 0 0)
			(layers "B.Cu" "B.Mask" "B.Paste")
			(net "PVDDCR_SOC_P0")
		)
		(pad "2" smd circle
			(at -0.40005 0 90)
			(size 0 0)
			(layers "B.Cu" "B.Mask" "B.Paste")
			(net "GND")
		)
	)
	(footprint ""
		(layer "B.Cu")
		(at 69.753734 -185.396632 90)
		(property "Reference" "PC281_1"
			(at 0 0 90)
			(layer "B.SilkS")
			(hide yes)
			(effects
				(font
					(size 1.27 1.27)
				)
				(justify mirror)
			)
		)
		(property "Value" ""
			(at 0 0 90)
			(layer "B.Fab")
			(effects
				(font
					(size 1.27 1.27)
				)
				(justify mirror)
			)
		)
		(duplicate_pad_numbers_are_jumpers no)
		(fp_line
			(start 1.524 -0.762)
			(end -1.524 -0.762)
			(stroke
				(width 0.1524)
				(type default)
			)
			(layer "B.SilkS")
		)
		(fp_line
			(start -1.524 -0.762)
			(end -1.524 0.762)
			(stroke
				(width 0.1524)
				(type default)
			)
			(layer "B.SilkS")
		)
		(fp_line
			(start 1.524 0.762)
			(end 1.524 -0.762)
			(stroke
				(width 0.1524)
				(type default)
			)
			(layer "B.SilkS")
		)
		(fp_line
			(start -1.524 0.762)
			(end 1.524 0.762)
			(stroke
				(width 0.1524)
				(type default)
			)
			(layer "B.SilkS")
		)
		(fp_line
			(start 1.1049 -0.724916)
			(end 1.1049 0.724916)
			(stroke
				(width 0.1)
				(type default)
			)
			(layer "B.Fab")
		)
		(fp_line
			(start -1.1049 -0.724916)
			(end 1.1049 -0.724916)
			(stroke
				(width 0.1)
				(type default)
			)
			(layer "B.Fab")
		)
		(fp_line
			(start 1.1049 0.724916)
			(end -1.1049 0.724916)
			(stroke
				(width 0.1)
				(type default)
			)
			(layer "B.Fab")
		)
		(fp_line
			(start -1.1049 0.724916)
			(end -1.1049 -0.724916)
			(stroke
				(width 0.1)
				(type default)
			)
			(layer "B.Fab")
		)
		(pad "1" smd rect
			(at 0.889 0 90)
			(size 1.016 1.27)
			(layers "B.Cu" "B.Mask" "B.Paste")
			(net "PVDDCR_CPU0_P1")
		)
		(pad "2" smd rect
			(at -0.889 0 90)
			(size 1.016 1.27)
			(layers "B.Cu" "B.Mask" "B.Paste")
			(net "GND")
		)
	)
	(footprint ""
		(layer "B.Cu")
		(at 91.966542 -151.376634 90)
		(property "Reference" "PR173"
			(at 0 0 90)
			(layer "B.SilkS")
			(hide yes)
			(effects
				(font
					(size 1.27 1.27)
				)
				(justify mirror)
			)
		)
		(property "Value" ""
			(at 0 0 90)
			(layer "B.Fab")
			(effects
				(font
					(size 1.27 1.27)
				)
				(justify mirror)
			)
		)
		(duplicate_pad_numbers_are_jumpers no)
		(fp_line
			(start 0.7874 -0.4064)
			(end -0.7874 -0.4064)
			(stroke
				(width 0.1524)
				(type default)
			)
			(layer "B.SilkS")
		)
		(fp_line
			(start -0.7874 -0.4064)
			(end -0.7874 0.4064)
			(stroke
				(width 0.1524)
				(type default)
			)
			(layer "B.SilkS")
		)
		(fp_line
			(start 0.7874 0.4064)
			(end 0.7874 -0.4064)
			(stroke
				(width 0.1524)
				(type default)
			)
			(layer "B.SilkS")
		)
		(fp_line
			(start -0.7874 0.4064)
			(end 0.7874 0.4064)
			(stroke
				(width 0.1524)
				(type default)
			)
			(layer "B.SilkS")
		)
		(fp_line
			(start 0.67945 -0.305054)
			(end 0.12065 -0.305054)
			(stroke
				(width 0.1)
				(type default)
			)
			(layer "B.Fab")
		)
		(fp_line
			(start 0.12065 -0.305054)
			(end 0.12065 -0.2794)
			(stroke
				(width 0.1)
				(type default)
			)
			(layer "B.Fab")
		)
		(fp_line
			(start -0.12065 -0.3048)
			(end -0.67945 -0.3048)
			(stroke
				(width 0.1)
				(type default)
			)
			(layer "B.Fab")
		)
		(fp_line
			(start -0.67945 -0.3048)
			(end -0.67945 0.3048)
			(stroke
				(width 0.1)
				(type default)
			)
			(layer "B.Fab")
		)
		(fp_line
			(start 0.12065 -0.2794)
			(end -0.12065 -0.2794)
			(stroke
				(width 0.1)
				(type default)
			)
			(layer "B.Fab")
		)
		(fp_line
			(start -0.12065 -0.2794)
			(end -0.12065 -0.3048)
			(stroke
				(width 0.1)
				(type default)
			)
			(layer "B.Fab")
		)
		(fp_line
			(start 0.12065 0.2794)
			(end 0.12065 0.3048)
			(stroke
				(width 0.1)
				(type default)
			)
			(layer "B.Fab")
		)
		(fp_line
			(start -0.120396 0.2794)
			(end 0.12065 0.2794)
			(stroke
				(width 0.1)
				(type default)
			)
			(layer "B.Fab")
		)
		(fp_line
			(start 0.67945 0.3048)
			(end 0.67945 -0.305054)
			(stroke
				(width 0.1)
				(type default)
			)
			(layer "B.Fab")
		)
		(fp_line
			(start 0.12065 0.3048)
			(end 0.67945 0.3048)
			(stroke
				(width 0.1)
				(type default)
			)
			(layer "B.Fab")
		)
		(fp_line
			(start -0.120396 0.3048)
			(end -0.120396 0.2794)
			(stroke
				(width 0.1)
				(type default)
			)
			(layer "B.Fab")
		)
		(fp_line
			(start -0.67945 0.3048)
			(end -0.120396 0.3048)
			(stroke
				(width 0.1)
				(type default)
			)
			(layer "B.Fab")
		)
		(pad "1" smd circle
			(at 0.40005 0 270)
			(size 0 0)
			(layers "B.Cu" "B.Mask" "B.Paste")
			(net "VSENSE_PVDDCR_CPU0_P1_DP")
		)
		(pad "2" smd circle
			(at -0.40005 0 270)
			(size 0 0)
			(layers "B.Cu" "B.Mask" "B.Paste")
			(net "VSENSE_PVDDCR_CPU0_P1_VSEN0")
		)
	)
)
